# S9S_MB_2U (Grand Teton) — schematic netlist excerpt (pin names and nets, part order shuffled) for the footprints in the layout excerpt that follows; sources: Cadence DE-HDL packaged netlist, KiCad conversion of 03242023_DA0F0TMBIJ0_F0T_Motherboard_J_brd_V01_OCP.brd

R4490  Q_RES  4.75K 1% EMPTY  pkg 0402LF  page 211 : A = CLK_9ZXL045_SADR0 ; B = GND
C930  Q_CAP_DIFFBUS  DIFF BUS_0.22UF 6.3V 20% X6S  pkg C0201  page 173 : \1\ = P5E_CPU0_PE0_TX_C_DN<1> ; \2\ = P5E_CPU0_PE0_TX_DN<1>
C1525  Q_CAP_DIFFBUS  DIFF BUS_0.22UF 6.3V 20% X6S  pkg C0201  page 177 : \1\ = P5E_CPU1_PE3_TX_C_DP<11> ; \2\ = P5E_CPU1_PE3_TX_DP<11>
PC2343  Q_CAP  22UF 16V 20% X6S  pkg C0805  page 259 : A = SW_P3V3_AUX_FLT ; B = GND

(kicad_pcb
	(version 20260206)
	(generator "pcbnew")
	(generator_version "10.0")
	(general
		(thickness 1.6)
		(legacy_teardrops no)
	)
	(paper "A4")
	(title_block
		(title "03242023_DA0F0TMBIJ0_F0T_Motherboard_J_brd_V01_OCP.brd")
		(comment 1 "Grand Teton / footprints 924-927 of 6105")
	)
	(layers
		(0 "F.Cu" signal "TOP")
		(4 "In1.Cu" signal "GND")
		(6 "In2.Cu" signal "IN1")
		(8 "In3.Cu" signal "GND1")
		(10 "In4.Cu" signal "IN2")
		(12 "In5.Cu" signal "GND2")
		(14 "In6.Cu" signal "IN3")
		(16 "In7.Cu" signal "GND3")
		(18 "In8.Cu" signal "VCC")
		(20 "In9.Cu" signal "VCC1")
		(22 "In10.Cu" signal "GND4")
		(24 "In11.Cu" signal "IN4")
		(26 "In12.Cu" signal "GND5")
		(28 "In13.Cu" signal "IN5")
		(30 "In14.Cu" signal "GND6")
		(32 "In15.Cu" signal "IN6")
		(34 "In16.Cu" signal "GND7")
		(2 "B.Cu" signal "BOTTOM")
		(9 "F.Adhes" user "F.Adhesive")
		(11 "B.Adhes" user "B.Adhesive")
		(13 "F.Paste" user "Package Geometry/Pastemask Top")
		(15 "B.Paste" user "Package Geometry/Pastemask Bottom")
		(5 "F.SilkS" user "Ref Des/Silkscreen Top")
		(7 "B.SilkS" user "Ref Des/Silkscreen Bottom")
		(1 "F.Mask" user "Board Geometry/Soldermask Top")
		(3 "B.Mask" user "Board Geometry/Soldermask Bottom")
		(17 "Dwgs.User" user "User.Drawings")
		(19 "Cmts.User" user "User.Comments")
		(21 "Eco1.User" user "User.Eco1")
		(23 "Eco2.User" user "User.Eco2")
		(25 "Edge.Cuts" user "Board Geometry/Outline")
		(27 "Margin" user)
		(31 "F.CrtYd" user "Package Geometry/Place Bound Top")
		(29 "B.CrtYd" user "Package Geometry/Place Bound Bottom")
		(35 "F.Fab" user "Ref Des/Assembly Top")
		(33 "B.Fab" user "Ref Des/Assembly Bottom")
	)
	(footprint ""
		(layer "F.Cu")
		(at 134.643114 -408.517344 -90)
		(property "Reference" "C1525"
			(at 0 0 270)
			(layer "F.SilkS")
			(hide yes)
			(effects
				(font
					(size 1.27 1.27)
				)
			)
		)
		(property "Value" ""
			(at 0 0 270)
			(layer "F.Fab")
			(effects
				(font
					(size 1.27 1.27)
				)
			)
		)
		(duplicate_pad_numbers_are_jumpers no)
		(fp_line
			(start -0.299974 0.150114)
			(end -0.299974 -0.150114)
			(stroke
				(width 0.1)
				(type default)
			)
			(layer "F.Fab")
		)
		(fp_line
			(start 0.299974 0.150114)
			(end -0.299974 0.150114)
			(stroke
				(width 0.1)
				(type default)
			)
			(layer "F.Fab")
		)
		(fp_line
			(start -0.299974 -0.150114)
			(end 0.299974 -0.150114)
			(stroke
				(width 0.1)
				(type default)
			)
			(layer "F.Fab")
		)
		(fp_line
			(start 0.299974 -0.150114)
			(end 0.299974 0.150114)
			(stroke
				(width 0.1)
				(type default)
			)
			(layer "F.Fab")
		)
		(pad "1" smd rect
			(at -0.2667 0 270)
			(size 0.3048 0.381)
			(layers "F.Cu" "F.Mask" "F.Paste")
			(net "P5E_CPU1_PE3_TX_C_DP<11>")
		)
		(pad "2" smd rect
			(at 0.2667 0 270)
			(size 0.3048 0.381)
			(layers "F.Cu" "F.Mask" "F.Paste")
			(net "P5E_CPU1_PE3_TX_DP<11>")
		)
	)
	(footprint ""
		(layer "F.Cu")
		(at 348.186248 -408.517344 -90)
		(property "Reference" "C930"
			(at 0 0 270)
			(layer "F.SilkS")
			(hide yes)
			(effects
				(font
					(size 1.27 1.27)
				)
			)
		)
		(property "Value" ""
			(at 0 0 270)
			(layer "F.Fab")
			(effects
				(font
					(size 1.27 1.27)
				)
			)
		)
		(duplicate_pad_numbers_are_jumpers no)
		(fp_line
			(start -0.299974 0.150114)
			(end -0.299974 -0.150114)
			(stroke
				(width 0.1)
				(type default)
			)
			(layer "F.Fab")
		)
		(fp_line
			(start 0.299974 0.150114)
			(end -0.299974 0.150114)
			(stroke
				(width 0.1)
				(type default)
			)
			(layer "F.Fab")
		)
		(fp_line
			(start -0.299974 -0.150114)
			(end 0.299974 -0.150114)
			(stroke
				(width 0.1)
				(type default)
			)
			(layer "F.Fab")
		)
		(fp_line
			(start 0.299974 -0.150114)
			(end 0.299974 0.150114)
			(stroke
				(width 0.1)
				(type default)
			)
			(layer "F.Fab")
		)
		(pad "1" smd rect
			(at -0.2667 0 270)
			(size 0.3048 0.381)
			(layers "F.Cu" "F.Mask" "F.Paste")
			(net "P5E_CPU0_PE0_TX_C_DN<1>")
		)
		(pad "2" smd rect
			(at 0.2667 0 270)
			(size 0.3048 0.381)
			(layers "F.Cu" "F.Mask" "F.Paste")
			(net "P5E_CPU0_PE0_TX_DN<1>")
		)
	)
	(footprint ""
		(layer "F.Cu")
		(at 123.6091 -414.283652)
		(property "Reference" "R4490"
			(at 0 0 0)
			(layer "F.SilkS")
			(hide yes)
			(effects
				(font
					(size 1.27 1.27)
				)
			)
		)
		(property "Value" ""
			(at 0 0 0)
			(layer "F.Fab")
			(effects
				(font
					(size 1.27 1.27)
				)
			)
		)
		(duplicate_pad_numbers_are_jumpers no)
		(fp_line
			(start -0.7874 -0.4064)
			(end 0.7874 -0.4064)
			(stroke
				(width 0.1524)
				(type default)
			)
			(layer "F.SilkS")
		)
		(fp_line
			(start -0.7874 0.4064)
			(end -0.7874 -0.4064)
			(stroke
				(width 0.1524)
				(type default)
			)
			(layer "F.SilkS")
		)
		(fp_line
			(start 0.7874 -0.4064)
			(end 0.7874 0.4064)
			(stroke
				(width 0.1524)
				(type default)
			)
			(layer "F.SilkS")
		)
		(fp_line
			(start 0.7874 0.4064)
			(end -0.7874 0.4064)
			(stroke
				(width 0.1524)
				(type default)
			)
			(layer "F.SilkS")
		)
		(fp_line
			(start -0.67945 -0.305054)
			(end -0.12065 -0.305054)
			(stroke
				(width 0.1)
				(type default)
			)
			(layer "F.Fab")
		)
		(fp_line
			(start -0.67945 0.3048)
			(end -0.67945 -0.305054)
			(stroke
				(width 0.1)
				(type default)
			)
			(layer "F.Fab")
		)
		(fp_line
			(start -0.12065 -0.305054)
			(end -0.12065 -0.2794)
			(stroke
				(width 0.1)
				(type default)
			)
			(layer "F.Fab")
		)
		(fp_line
			(start -0.12065 -0.2794)
			(end 0.12065 -0.2794)
			(stroke
				(width 0.1)
				(type default)
			)
			(layer "F.Fab")
		)
		(fp_line
			(start -0.12065 0.2794)
			(end -0.12065 0.3048)
			(stroke
				(width 0.1)
				(type default)
			)
			(layer "F.Fab")
		)
		(fp_line
			(start -0.12065 0.3048)
			(end -0.67945 0.3048)
			(stroke
				(width 0.1)
				(type default)
			)
			(layer "F.Fab")
		)
		(fp_line
			(start 0.120396 0.2794)
			(end -0.12065 0.2794)
			(stroke
				(width 0.1)
				(type default)
			)
			(layer "F.Fab")
		)
		(fp_line
			(start 0.120396 0.3048)
			(end 0.120396 0.2794)
			(stroke
				(width 0.1)
				(type default)
			)
			(layer "F.Fab")
		)
		(fp_line
			(start 0.12065 -0.3048)
			(end 0.67945 -0.3048)
			(stroke
				(width 0.1)
				(type default)
			)
			(layer "F.Fab")
		)
		(fp_line
			(start 0.12065 -0.2794)
			(end 0.12065 -0.3048)
			(stroke
				(width 0.1)
				(type default)
			)
			(layer "F.Fab")
		)
		(fp_line
			(start 0.67945 -0.3048)
			(end 0.67945 0.3048)
			(stroke
				(width 0.1)
				(type default)
			)
			(layer "F.Fab")
		)
		(fp_line
			(start 0.67945 0.3048)
			(end 0.120396 0.3048)
			(stroke
				(width 0.1)
				(type default)
			)
			(layer "F.Fab")
		)
		(pad "1" smd circle
			(at -0.40005 0)
			(size 0 0)
			(layers "F.Cu" "F.Mask" "F.Paste")
			(net "CLK_9ZXL045_SADR0")
		)
		(pad "2" smd circle
			(at 0.40005 0)
			(size 0 0)
			(layers "F.Cu" "F.Mask" "F.Paste")
			(net "GND")
		)
	)
	(footprint ""
		(layer "F.Cu")
		(at 454.742804 -76.588112 90)
		(property "Reference" "PC2343"
			(at 0 0 90)
			(layer "F.SilkS")
			(hide yes)
			(effects
				(font
					(size 1.27 1.27)
				)
			)
		)
		(property "Value" ""
			(at 0 0 90)
			(layer "F.Fab")
			(effects
				(font
					(size 1.27 1.27)
				)
			)
		)
		(duplicate_pad_numbers_are_jumpers no)
		(fp_line
			(start 1.524 -0.762)
			(end 1.524 0.762)
			(stroke
				(width 0.1524)
				(type default)
			)
			(layer "F.SilkS")
		)
		(fp_line
			(start -1.524 -0.762)
			(end 1.524 -0.762)
			(stroke
				(width 0.1524)
				(type default)
			)
			(layer "F.SilkS")
		)
		(fp_line
			(start 1.524 0.762)
			(end -1.524 0.762)
			(stroke
				(width 0.1524)
				(type default)
			)
			(layer "F.SilkS")
		)
		(fp_line
			(start -1.524 0.762)
			(end -1.524 -0.762)
			(stroke
				(width 0.1524)
				(type default)
			)
			(layer "F.SilkS")
		)
		(fp_line
			(start 1.1049 -0.724916)
			(end -1.1049 -0.724916)
			(stroke
				(width 0.1)
				(type default)
			)
			(layer "F.Fab")
		)
		(fp_line
			(start -1.1049 -0.724916)
			(end -1.1049 0.724916)
			(stroke
				(width 0.1)
				(type default)
			)
			(layer "F.Fab")
		)
		(fp_line
			(start 1.1049 0.724916)
			(end 1.1049 -0.724916)
			(stroke
				(width 0.1)
				(type default)
			)
			(layer "F.Fab")
		)
		(fp_line
			(start -1.1049 0.724916)
			(end 1.1049 0.724916)
			(stroke
				(width 0.1)
				(type default)
			)
			(layer "F.Fab")
		)
		(pad "1" smd rect
			(at -0.889 0 270)
			(size 1.016 1.27)
			(layers "F.Cu" "F.Mask" "F.Paste")
			(net "SW_P3V3_AUX_FLT")
		)
		(pad "2" smd rect
			(at 0.889 0 270)
			(size 1.016 1.27)
			(layers "F.Cu" "F.Mask" "F.Paste")
			(net "GND")
		)
	)
)
